# S9S_MB_2U (Grand Teton) — schematic netlist excerpt (pin names and nets, part order shuffled) for the footprints in the layout excerpt that follows; sources: Cadence DE-HDL packaged netlist, KiCad conversion of 03242023_DA0F0TMBIJ0_F0T_Motherboard_J_brd_V01_OCP.brd

C484  Q_CAP  47UF 4V 20% X6S  pkg C0805  page 79 : A = PVCCINFAON_CPU1 ; B = GND
R1003  Q_RES  4.7K 5% CHIP  pkg 0402LF  page 235 : A = P3V3 ; B = FM_SMB_CPU1_ALERT_R1
C116  Q_CAP  0.047UF 25V 10% X7R  pkg C0402  page 210 : A = P3V3_AUX_CLK_GEN_VDDMXCK_CK440 ; B = GND

(kicad_pcb
	(version 20260206)
	(generator "pcbnew")
	(generator_version "10.0")
	(general
		(thickness 1.6)
		(legacy_teardrops no)
	)
	(paper "A4")
	(title_block
		(title "03242023_DA0F0TMBIJ0_F0T_Motherboard_J_brd_V01_OCP.brd")
		(comment 1 "Grand Teton / footprints 5038-5040 of 6105")
	)
	(layers
		(0 "F.Cu" signal "TOP")
		(4 "In1.Cu" signal "GND")
		(6 "In2.Cu" signal "IN1")
		(8 "In3.Cu" signal "GND1")
		(10 "In4.Cu" signal "IN2")
		(12 "In5.Cu" signal "GND2")
		(14 "In6.Cu" signal "IN3")
		(16 "In7.Cu" signal "GND3")
		(18 "In8.Cu" signal "VCC")
		(20 "In9.Cu" signal "VCC1")
		(22 "In10.Cu" signal "GND4")
		(24 "In11.Cu" signal "IN4")
		(26 "In12.Cu" signal "GND5")
		(28 "In13.Cu" signal "IN5")
		(30 "In14.Cu" signal "GND6")
		(32 "In15.Cu" signal "IN6")
		(34 "In16.Cu" signal "GND7")
		(2 "B.Cu" signal "BOTTOM")
		(9 "F.Adhes" user "F.Adhesive")
		(11 "B.Adhes" user "B.Adhesive")
		(13 "F.Paste" user "Package Geometry/Pastemask Top")
		(15 "B.Paste" user "Package Geometry/Pastemask Bottom")
		(5 "F.SilkS" user "Ref Des/Silkscreen Top")
		(7 "B.SilkS" user "Ref Des/Silkscreen Bottom")
		(1 "F.Mask" user "Board Geometry/Soldermask Top")
		(3 "B.Mask" user "Board Geometry/Soldermask Bottom")
		(17 "Dwgs.User" user "User.Drawings")
		(19 "Cmts.User" user "User.Comments")
		(21 "Eco1.User" user "User.Eco1")
		(23 "Eco2.User" user "User.Eco2")
		(25 "Edge.Cuts" user "Board Geometry/Outline")
		(27 "Margin" user)
		(31 "F.CrtYd" user "Package Geometry/Place Bound Top")
		(29 "B.CrtYd" user "Package Geometry/Place Bound Bottom")
		(35 "F.Fab" user "Ref Des/Assembly Top")
		(33 "B.Fab" user "Ref Des/Assembly Bottom")
	)
	(footprint ""
		(layer "B.Cu")
		(at 258.953 -101.183948)
		(property "Reference" "C116"
			(at 0 0 0)
			(layer "B.SilkS")
			(hide yes)
			(effects
				(font
					(size 1.27 1.27)
				)
				(justify mirror)
			)
		)
		(property "Value" ""
			(at 0 0 0)
			(layer "B.Fab")
			(effects
				(font
					(size 1.27 1.27)
				)
				(justify mirror)
			)
		)
		(duplicate_pad_numbers_are_jumpers no)
		(fp_line
			(start -0.7874 -0.4064)
			(end -0.7874 0.4064)
			(stroke
				(width 0.1524)
				(type default)
			)
			(layer "B.SilkS")
		)
		(fp_line
			(start -0.7874 0.4064)
			(end 0.7874 0.4064)
			(stroke
				(width 0.1524)
				(type default)
			)
			(layer "B.SilkS")
		)
		(fp_line
			(start 0.7874 -0.4064)
			(end -0.7874 -0.4064)
			(stroke
				(width 0.1524)
				(type default)
			)
			(layer "B.SilkS")
		)
		(fp_line
			(start 0.7874 0.4064)
			(end 0.7874 -0.4064)
			(stroke
				(width 0.1524)
				(type default)
			)
			(layer "B.SilkS")
		)
		(fp_line
			(start -0.67945 -0.3048)
			(end -0.67945 0.3048)
			(stroke
				(width 0.1)
				(type default)
			)
			(layer "B.Fab")
		)
		(fp_line
			(start -0.67945 0.3048)
			(end -0.120396 0.3048)
			(stroke
				(width 0.1)
				(type default)
			)
			(layer "B.Fab")
		)
		(fp_line
			(start -0.12065 -0.3048)
			(end -0.67945 -0.3048)
			(stroke
				(width 0.1)
				(type default)
			)
			(layer "B.Fab")
		)
		(fp_line
			(start -0.12065 -0.2794)
			(end -0.12065 -0.3048)
			(stroke
				(width 0.1)
				(type default)
			)
			(layer "B.Fab")
		)
		(fp_line
			(start -0.120396 0.2794)
			(end 0.12065 0.2794)
			(stroke
				(width 0.1)
				(type default)
			)
			(layer "B.Fab")
		)
		(fp_line
			(start -0.120396 0.3048)
			(end -0.120396 0.2794)
			(stroke
				(width 0.1)
				(type default)
			)
			(layer "B.Fab")
		)
		(fp_line
			(start 0.12065 -0.305054)
			(end 0.12065 -0.2794)
			(stroke
				(width 0.1)
				(type default)
			)
			(layer "B.Fab")
		)
		(fp_line
			(start 0.12065 -0.2794)
			(end -0.12065 -0.2794)
			(stroke
				(width 0.1)
				(type default)
			)
			(layer "B.Fab")
		)
		(fp_line
			(start 0.12065 0.2794)
			(end 0.12065 0.3048)
			(stroke
				(width 0.1)
				(type default)
			)
			(layer "B.Fab")
		)
		(fp_line
			(start 0.12065 0.3048)
			(end 0.67945 0.3048)
			(stroke
				(width 0.1)
				(type default)
			)
			(layer "B.Fab")
		)
		(fp_line
			(start 0.67945 -0.305054)
			(end 0.12065 -0.305054)
			(stroke
				(width 0.1)
				(type default)
			)
			(layer "B.Fab")
		)
		(fp_line
			(start 0.67945 0.3048)
			(end 0.67945 -0.305054)
			(stroke
				(width 0.1)
				(type default)
			)
			(layer "B.Fab")
		)
		(pad "1" smd circle
			(at 0.40005 0 180)
			(size 0 0)
			(layers "B.Cu" "B.Mask" "B.Paste")
			(net "P3V3_AUX_CLK_GEN_VDDMXCK_CK440")
		)
		(pad "2" smd circle
			(at -0.40005 0 180)
			(size 0 0)
			(layers "B.Cu" "B.Mask" "B.Paste")
			(net "GND")
		)
	)
	(footprint ""
		(layer "B.Cu")
		(at 121.581926 -212.049868 180)
		(property "Reference" "C484"
			(at 0 0 0)
			(layer "B.SilkS")
			(hide yes)
			(effects
				(font
					(size 1.27 1.27)
				)
				(justify mirror)
			)
		)
		(property "Value" ""
			(at 0 0 0)
			(layer "B.Fab")
			(effects
				(font
					(size 1.27 1.27)
				)
				(justify mirror)
			)
		)
		(duplicate_pad_numbers_are_jumpers no)
		(fp_line
			(start 1.524 0.762)
			(end 1.524 -0.762)
			(stroke
				(width 0.1524)
				(type default)
			)
			(layer "B.SilkS")
		)
		(fp_line
			(start 1.524 -0.762)
			(end -1.524 -0.762)
			(stroke
				(width 0.1524)
				(type default)
			)
			(layer "B.SilkS")
		)
		(fp_line
			(start -1.524 0.762)
			(end 1.524 0.762)
			(stroke
				(width 0.1524)
				(type default)
			)
			(layer "B.SilkS")
		)
		(fp_line
			(start -1.524 -0.762)
			(end -1.524 0.762)
			(stroke
				(width 0.1524)
				(type default)
			)
			(layer "B.SilkS")
		)
		(fp_line
			(start 1.1049 0.724916)
			(end -1.1049 0.724916)
			(stroke
				(width 0.1)
				(type default)
			)
			(layer "B.Fab")
		)
		(fp_line
			(start 1.1049 -0.724916)
			(end 1.1049 0.724916)
			(stroke
				(width 0.1)
				(type default)
			)
			(layer "B.Fab")
		)
		(fp_line
			(start -1.1049 0.724916)
			(end -1.1049 -0.724916)
			(stroke
				(width 0.1)
				(type default)
			)
			(layer "B.Fab")
		)
		(fp_line
			(start -1.1049 -0.724916)
			(end 1.1049 -0.724916)
			(stroke
				(width 0.1)
				(type default)
			)
			(layer "B.Fab")
		)
		(pad "1" smd rect
			(at 0.889 0 180)
			(size 1.016 1.27)
			(layers "B.Cu" "B.Mask" "B.Paste")
			(net "PVCCINFAON_CPU1")
		)
		(pad "2" smd rect
			(at -0.889 0 180)
			(size 1.016 1.27)
			(layers "B.Cu" "B.Mask" "B.Paste")
			(net "GND")
		)
	)
	(footprint ""
		(layer "B.Cu")
		(at 89.661238 -179.31511)
		(property "Reference" "R1003"
			(at 0 0 0)
			(layer "B.SilkS")
			(hide yes)
			(effects
				(font
					(size 1.27 1.27)
				)
				(justify mirror)
			)
		)
		(property "Value" ""
			(at 0 0 0)
			(layer "B.Fab")
			(effects
				(font
					(size 1.27 1.27)
				)
				(justify mirror)
			)
		)
		(duplicate_pad_numbers_are_jumpers no)
		(fp_line
			(start -0.7874 -0.4064)
			(end -0.7874 0.4064)
			(stroke
				(width 0.1524)
				(type default)
			)
			(layer "B.SilkS")
		)
		(fp_line
			(start -0.7874 0.4064)
			(end 0.7874 0.4064)
			(stroke
				(width 0.1524)
				(type default)
			)
			(layer "B.SilkS")
		)
		(fp_line
			(start 0.7874 -0.4064)
			(end -0.7874 -0.4064)
			(stroke
				(width 0.1524)
				(type default)
			)
			(layer "B.SilkS")
		)
		(fp_line
			(start 0.7874 0.4064)
			(end 0.7874 -0.4064)
			(stroke
				(width 0.1524)
				(type default)
			)
			(layer "B.SilkS")
		)
		(fp_line
			(start -0.67945 -0.3048)
			(end -0.67945 0.3048)
			(stroke
				(width 0.1)
				(type default)
			)
			(layer "B.Fab")
		)
		(fp_line
			(start -0.67945 0.3048)
			(end -0.120396 0.3048)
			(stroke
				(width 0.1)
				(type default)
			)
			(layer "B.Fab")
		)
		(fp_line
			(start -0.12065 -0.3048)
			(end -0.67945 -0.3048)
			(stroke
				(width 0.1)
				(type default)
			)
			(layer "B.Fab")
		)
		(fp_line
			(start -0.12065 -0.2794)
			(end -0.12065 -0.3048)
			(stroke
				(width 0.1)
				(type default)
			)
			(layer "B.Fab")
		)
		(fp_line
			(start -0.120396 0.2794)
			(end 0.12065 0.2794)
			(stroke
				(width 0.1)
				(type default)
			)
			(layer "B.Fab")
		)
		(fp_line
			(start -0.120396 0.3048)
			(end -0.120396 0.2794)
			(stroke
				(width 0.1)
				(type default)
			)
			(layer "B.Fab")
		)
		(fp_line
			(start 0.12065 -0.305054)
			(end 0.12065 -0.2794)
			(stroke
				(width 0.1)
				(type default)
			)
			(layer "B.Fab")
		)
		(fp_line
			(start 0.12065 -0.2794)
			(end -0.12065 -0.2794)
			(stroke
				(width 0.1)
				(type default)
			)
			(layer "B.Fab")
		)
		(fp_line
			(start 0.12065 0.2794)
			(end 0.12065 0.3048)
			(stroke
				(width 0.1)
				(type default)
			)
			(layer "B.Fab")
		)
		(fp_line
			(start 0.12065 0.3048)
			(end 0.67945 0.3048)
			(stroke
				(width 0.1)
				(type default)
			)
			(layer "B.Fab")
		)
		(fp_line
			(start 0.67945 -0.305054)
			(end 0.12065 -0.305054)
			(stroke
				(width 0.1)
				(type default)
			)
			(layer "B.Fab")
		)
		(fp_line
			(start 0.67945 0.3048)
			(end 0.67945 -0.305054)
			(stroke
				(width 0.1)
				(type default)
			)
			(layer "B.Fab")
		)
		(pad "1" smd circle
			(at 0.40005 0 180)
			(size 0 0)
			(layers "B.Cu" "B.Mask" "B.Paste")
			(net "P3V3")
		)
		(pad "2" smd circle
			(at -0.40005 0 180)
			(size 0 0)
			(layers "B.Cu" "B.Mask" "B.Paste")
			(net "FM_SMB_CPU1_ALERT_R1")
		)
	)
)
